(kicad_pcb
	(version 20260206)
	(generator "pcbnew")
	(generator_version "10.0")
	(general
		(thickness 1.6)
		(legacy_teardrops no)
	)
	(paper "A4")
	(title_block
		(title "01162023_DA0F0TEBIF0_F0T_Expander_BD_F_brd_V02_OCP.brd")
		(comment 1 "Grand Teton / footprints 6902-6908 of 9728")
	)
	(layers
		(0 "F.Cu" signal "TOP")
		(4 "In1.Cu" signal "GND")
		(6 "In2.Cu" signal "VCC")
		(8 "In3.Cu" signal "VCC1")
		(10 "In4.Cu" signal "GND1")
		(12 "In5.Cu" signal "IN1")
		(14 "In6.Cu" signal "GND2")
		(16 "In7.Cu" signal "IN2")
		(18 "In8.Cu" signal "GND3")
		(20 "In9.Cu" signal "IN3")
		(22 "In10.Cu" signal "GND4")
		(24 "In11.Cu" signal "IN4")
		(26 "In12.Cu" signal "GND5")
		(28 "In13.Cu" signal "IN5")
		(30 "In14.Cu" signal "GND6")
		(32 "In15.Cu" signal "IN6")
		(34 "In16.Cu" signal "GND7")
		(2 "B.Cu" signal "BOTTOM")
		(9 "F.Adhes" user "F.Adhesive")
		(11 "B.Adhes" user "B.Adhesive")
		(13 "F.Paste" user "Package Geometry/Pastemask Top")
		(15 "B.Paste" user "Package Geometry/Pastemask Bottom")
		(5 "F.SilkS" user "Ref Des/Silkscreen Top")
		(7 "B.SilkS" user "Ref Des/Silkscreen Bottom")
		(1 "F.Mask" user "Board Geometry/Soldermask Top")
		(3 "B.Mask" user "Board Geometry/Soldermask Bottom")
		(17 "Dwgs.User" user "User.Drawings")
		(19 "Cmts.User" user "User.Comments")
		(21 "Eco1.User" user "User.Eco1")
		(23 "Eco2.User" user "User.Eco2")
		(25 "Edge.Cuts" user "Board Geometry/Outline")
		(27 "Margin" user)
		(31 "F.CrtYd" user "Package Geometry/Place Bound Top")
		(29 "B.CrtYd" user "Package Geometry/Place Bound Bottom")
		(35 "F.Fab" user "Ref Des/Assembly Top")
		(33 "B.Fab" user "Ref Des/Assembly Bottom")
	)
	(footprint ""
		(layer "F.Cu")
		(at 320.354452 -220.849698 180)
		(property "Reference" "D17"
			(at 3.743452 0.103632 0)
			(unlocked yes)
			(layer "F.SilkS")
			(effects
				(font
					(size 0.7874 0.5842)
					(thickness 0.1524)
				)
				(justify left)
			)
		)
		(property "Value" ""
			(at 0 0 180)
			(layer "F.Fab")
			(effects
				(font
					(size 1.27 1.27)
				)
			)
		)
		(duplicate_pad_numbers_are_jumpers no)
		(fp_line
			(start 1.16078 0.4826)
			(end -0.64008 0.4826)
			(stroke
				(width 0.1524)
				(type default)
			)
			(layer "F.SilkS")
		)
		(fp_line
			(start 1.16078 -0.4826)
			(end 1.16078 0.4826)
			(stroke
				(width 0.1524)
				(type default)
			)
			(layer "F.SilkS")
		)
		(fp_line
			(start 1.03378 0.4826)
			(end -0.79248 0.4826)
			(stroke
				(width 0.1524)
				(type default)
			)
			(layer "F.SilkS")
		)
		(fp_line
			(start 1.03378 -0.4826)
			(end 1.03378 0.4826)
			(stroke
				(width 0.1524)
				(type default)
			)
			(layer "F.SilkS")
		)
		(fp_line
			(start 0.90678 0.4826)
			(end -0.90678 0.4826)
			(stroke
				(width 0.1524)
				(type default)
			)
			(layer "F.SilkS")
		)
		(fp_line
			(start 0.90678 -0.4826)
			(end 0.90678 0.4826)
			(stroke
				(width 0.1524)
				(type default)
			)
			(layer "F.SilkS")
		)
		(fp_line
			(start -0.64008 -0.4826)
			(end 1.16078 -0.4826)
			(stroke
				(width 0.1524)
				(type default)
			)
			(layer "F.SilkS")
		)
		(fp_line
			(start -0.79248 -0.4826)
			(end 1.03378 -0.4826)
			(stroke
				(width 0.1524)
				(type default)
			)
			(layer "F.SilkS")
		)
		(fp_line
			(start -0.89408 -0.4826)
			(end 0.90678 -0.4826)
			(stroke
				(width 0.1524)
				(type default)
			)
			(layer "F.SilkS")
		)
		(fp_line
			(start -0.90678 0.4826)
			(end -0.90678 -0.4699)
			(stroke
				(width 0.1524)
				(type default)
			)
			(layer "F.SilkS")
		)
		(fp_line
			(start 0.499872 0.249936)
			(end -0.499872 0.249936)
			(stroke
				(width 0.1)
				(type default)
			)
			(layer "F.Fab")
		)
		(fp_line
			(start 0.499872 -0.249936)
			(end 0.499872 0.249936)
			(stroke
				(width 0.1)
				(type default)
			)
			(layer "F.Fab")
		)
		(fp_line
			(start -0.499872 0.249936)
			(end -0.499872 -0.249936)
			(stroke
				(width 0.1)
				(type default)
			)
			(layer "F.Fab")
		)
		(fp_line
			(start -0.499872 -0.249936)
			(end 0.499872 -0.249936)
			(stroke
				(width 0.1)
				(type default)
			)
			(layer "F.Fab")
		)
		(pad "A" smd rect
			(at -0.47498 0 180)
			(size 0.6096 0.7112)
			(layers "F.Cu" "F.Mask" "F.Paste")
			(net "LED_POSTCODE_R_4")
		)
		(pad "C" smd rect
			(at 0.47498 0 180)
			(size 0.6096 0.7112)
			(layers "F.Cu" "F.Mask" "F.Paste")
			(net "FPGA_DEBUG_LED_R_N")
		)
	)
	(footprint ""
		(layer "F.Cu")
		(at 247.67159 -211.276946)
		(property "Reference" "C4458"
			(at 0 0 0)
			(layer "F.SilkS")
			(hide yes)
			(effects
				(font
					(size 1.27 1.27)
				)
			)
		)
		(property "Value" ""
			(at 0 0 0)
			(layer "F.Fab")
			(effects
				(font
					(size 1.27 1.27)
				)
			)
		)
		(duplicate_pad_numbers_are_jumpers no)
		(fp_line
			(start -0.7874 -0.4064)
			(end 0.7874 -0.4064)
			(stroke
				(width 0.1524)
				(type default)
			)
			(layer "F.SilkS")
		)
		(fp_line
			(start -0.7874 0.4064)
			(end -0.7874 -0.4064)
			(stroke
				(width 0.1524)
				(type default)
			)
			(layer "F.SilkS")
		)
		(fp_line
			(start 0.7874 -0.4064)
			(end 0.7874 0.4064)
			(stroke
				(width 0.1524)
				(type default)
			)
			(layer "F.SilkS")
		)
		(fp_line
			(start 0.7874 0.4064)
			(end -0.7874 0.4064)
			(stroke
				(width 0.1524)
				(type default)
			)
			(layer "F.SilkS")
		)
		(fp_line
			(start -0.67945 -0.305054)
			(end -0.12065 -0.305054)
			(stroke
				(width 0.1)
				(type default)
			)
			(layer "F.Fab")
		)
		(fp_line
			(start -0.67945 0.3048)
			(end -0.67945 -0.305054)
			(stroke
				(width 0.1)
				(type default)
			)
			(layer "F.Fab")
		)
		(fp_line
			(start -0.12065 -0.305054)
			(end -0.12065 -0.2794)
			(stroke
				(width 0.1)
				(type default)
			)
			(layer "F.Fab")
		)
		(fp_line
			(start -0.12065 -0.2794)
			(end 0.12065 -0.2794)
			(stroke
				(width 0.1)
				(type default)
			)
			(layer "F.Fab")
		)
		(fp_line
			(start -0.12065 0.2794)
			(end -0.12065 0.3048)
			(stroke
				(width 0.1)
				(type default)
			)
			(layer "F.Fab")
		)
		(fp_line
			(start -0.12065 0.3048)
			(end -0.67945 0.3048)
			(stroke
				(width 0.1)
				(type default)
			)
			(layer "F.Fab")
		)
		(fp_line
			(start 0.120396 0.2794)
			(end -0.12065 0.2794)
			(stroke
				(width 0.1)
				(type default)
			)
			(layer "F.Fab")
		)
		(fp_line
			(start 0.120396 0.3048)
			(end 0.120396 0.2794)
			(stroke
				(width 0.1)
				(type default)
			)
			(layer "F.Fab")
		)
		(fp_line
			(start 0.12065 -0.3048)
			(end 0.67945 -0.3048)
			(stroke
				(width 0.1)
				(type default)
			)
			(layer "F.Fab")
		)
		(fp_line
			(start 0.12065 -0.2794)
			(end 0.12065 -0.3048)
			(stroke
				(width 0.1)
				(type default)
			)
			(layer "F.Fab")
		)
		(fp_line
			(start 0.67945 -0.3048)
			(end 0.67945 0.3048)
			(stroke
				(width 0.1)
				(type default)
			)
			(layer "F.Fab")
		)
		(fp_line
			(start 0.67945 0.3048)
			(end 0.120396 0.3048)
			(stroke
				(width 0.1)
				(type default)
			)
			(layer "F.Fab")
		)
		(pad "1" smd circle
			(at -0.40005 0)
			(size 0 0)
			(layers "F.Cu" "F.Mask" "F.Paste")
			(net "HSC_TYPE_ADC_R")
		)
		(pad "2" smd circle
			(at 0.40005 0)
			(size 0 0)
			(layers "F.Cu" "F.Mask" "F.Paste")
			(net "GND")
		)
	)
	(footprint ""
		(layer "F.Cu")
		(at 334.240124 -356.244906 90)
		(property "Reference" "C527"
			(at 0 0 90)
			(layer "F.SilkS")
			(hide yes)
			(effects
				(font
					(size 1.27 1.27)
				)
			)
		)
		(property "Value" ""
			(at 0 0 90)
			(layer "F.Fab")
			(effects
				(font
					(size 1.27 1.27)
				)
			)
		)
		(duplicate_pad_numbers_are_jumpers no)
		(fp_line
			(start 0.299974 -0.150114)
			(end 0.299974 0.150114)
			(stroke
				(width 0.1)
				(type default)
			)
			(layer "F.Fab")
		)
		(fp_line
			(start -0.299974 -0.150114)
			(end 0.299974 -0.150114)
			(stroke
				(width 0.1)
				(type default)
			)
			(layer "F.Fab")
		)
		(fp_line
			(start 0.299974 0.150114)
			(end -0.299974 0.150114)
			(stroke
				(width 0.1)
				(type default)
			)
			(layer "F.Fab")
		)
		(fp_line
			(start -0.299974 0.150114)
			(end -0.299974 -0.150114)
			(stroke
				(width 0.1)
				(type default)
			)
			(layer "F.Fab")
		)
		(pad "1" smd rect
			(at -0.2667 0 90)
			(size 0.3048 0.381)
			(layers "F.Cu" "F.Mask" "F.Paste")
			(net "P5E_PEX2_STN5_TX_DP<91>")
		)
		(pad "2" smd rect
			(at 0.2667 0 90)
			(size 0.3048 0.381)
			(layers "F.Cu" "F.Mask" "F.Paste")
			(net "P5E_PEX2_STN5_TX_C_DP<91>")
		)
	)
	(footprint ""
		(layer "F.Cu")
		(at 407.800048 -407.960068 180)
		(property "Reference" "J62"
			(at -2.6289 -11.325352 0)
			(unlocked yes)
			(layer "F.SilkS")
			(effects
				(font
					(size 0.7874 0.5842)
					(thickness 0.1524)
				)
			)
		)
		(property "Value" ""
			(at 0 0 180)
			(layer "F.Fab")
			(effects
				(font
					(size 1.27 1.27)
				)
			)
		)
		(duplicate_pad_numbers_are_jumpers no)
		(fp_line
			(start 3.525012 21.310092)
			(end 3.525012 -10.489946)
			(stroke
				(width 0.1524)
				(type default)
			)
			(layer "F.SilkS")
		)
		(fp_line
			(start 3.525012 -10.489946)
			(end -3.525012 -10.489946)
			(stroke
				(width 0.1524)
				(type default)
			)
			(layer "F.SilkS")
		)
		(fp_line
			(start -3.525012 21.310092)
			(end 3.525012 21.310092)
			(stroke
				(width 0.1524)
				(type default)
			)
			(layer "F.SilkS")
		)
		(fp_line
			(start -3.525012 10.6299)
			(end 3.525012 10.6299)
			(stroke
				(width 0.1524)
				(type default)
			)
			(layer "F.SilkS")
		)
		(fp_line
			(start -3.525012 -10.489946)
			(end -3.525012 21.310092)
			(stroke
				(width 0.1524)
				(type default)
			)
			(layer "F.SilkS")
		)
		(fp_line
			(start 3.525012 21.310092)
			(end 3.525012 -10.489946)
			(stroke
				(width 0.1)
				(type default)
			)
			(layer "F.Fab")
		)
		(fp_line
			(start 3.525012 -10.489946)
			(end -3.525012 -10.489946)
			(stroke
				(width 0.1)
				(type default)
			)
			(layer "F.Fab")
		)
		(fp_line
			(start -3.525012 21.310092)
			(end 3.525012 21.310092)
			(stroke
				(width 0.1)
				(type default)
			)
			(layer "F.Fab")
		)
		(fp_line
			(start -3.525012 -10.489946)
			(end -3.525012 21.310092)
			(stroke
				(width 0.1)
				(type default)
			)
			(layer "F.Fab")
		)
		(pad "" np_thru_hole circle
			(at 0 -6.620002 180)
			(size 3.175 3.175)
			(drill 3.175)
			(layers "*.Cu" "*.Mask")
			(clearance 0.381)
			(thermal_gap 0.381)
		)
		(pad "" np_thru_hole circle
			(at 0 0 180)
			(size 0 0)
			(drill 3.175)
			(layers "*.Cu" "*.Mask")
			(clearance 0)
		)
		(pad "" np_thru_hole circle
			(at 0 5.130038 180)
			(size 3.175 3.175)
			(drill 3.175)
			(layers "*.Cu" "*.Mask")
			(clearance 0.381)
			(thermal_gap 0.381)
		)
		(zone
			(layers "F.Cu" "B.Cu" "In1.Cu" "In2.Cu" "In3.Cu" "In4.Cu" "In5.Cu" "In6.Cu"
				"In7.Cu" "In8.Cu" "In9.Cu" "In10.Cu" "In11.Cu" "In12.Cu" "In13.Cu" "In14.Cu"
				"In15.Cu" "In16.Cu"
			)
			(hatch none 0.5)
			(connect_pads
				(clearance 0)
			)
			(min_thickness 0.25)
			(keepout
				(tracks not_allowed)
				(vias allowed)
				(pads allowed)
				(copperpour not_allowed)
				(footprints allowed)
			)
			(placement
				(enabled no)
				(sheetname "")
			)
			(fill
				(thermal_gap 0.5)
				(thermal_bridge_width 0.5)
				(island_removal_mode 0)
			)
			(polygon
				(pts
					(arc
						(start 409.895548 -413.090106)
						(mid 405.704548 -413.090106)
						(end 409.895548 -413.090106)
					)
				)
			)
		)
		(zone
			(layers "F.Cu" "B.Cu" "In1.Cu" "In2.Cu" "In3.Cu" "In4.Cu" "In5.Cu" "In6.Cu"
				"In7.Cu" "In8.Cu" "In9.Cu" "In10.Cu" "In11.Cu" "In12.Cu" "In13.Cu" "In14.Cu"
				"In15.Cu" "In16.Cu"
			)
			(hatch none 0.5)
			(connect_pads
				(clearance 0)
			)
			(min_thickness 0.25)
			(keepout
				(tracks not_allowed)
				(vias allowed)
				(pads allowed)
				(copperpour not_allowed)
				(footprints allowed)
			)
			(placement
				(enabled no)
				(sheetname "")
			)
			(fill
				(thermal_gap 0.5)
				(thermal_bridge_width 0.5)
				(island_removal_mode 0)
			)
			(polygon
				(pts
					(arc
						(start 409.895548 -401.340066)
						(mid 405.704548 -401.340066)
						(end 409.895548 -401.340066)
					)
				)
			)
		)
		(zone
			(layers "F.Cu" "B.Cu" "In1.Cu" "In2.Cu" "In3.Cu" "In4.Cu" "In5.Cu" "In6.Cu"
				"In7.Cu" "In8.Cu" "In9.Cu" "In10.Cu" "In11.Cu" "In12.Cu" "In13.Cu" "In14.Cu"
				"In15.Cu" "In16.Cu"
			)
			(hatch none 0.5)
			(connect_pads
				(clearance 0)
			)
			(min_thickness 0.25)
			(keepout
				(tracks not_allowed)
				(vias allowed)
				(pads allowed)
				(copperpour not_allowed)
				(footprints allowed)
			)
			(placement
				(enabled no)
				(sheetname "")
			)
			(fill
				(thermal_gap 0.5)
				(thermal_bridge_width 0.5)
				(island_removal_mode 0)
			)
			(polygon
				(pts
					(arc
						(start 411.419548 -407.960068)
						(mid 404.180548 -407.960068)
						(end 411.419548 -407.960068)
					)
				)
			)
		)
	)
	(footprint ""
		(layer "F.Cu")
		(at 447.275712 -121.509028)
		(property "Reference" "PR254"
			(at 0 0 0)
			(layer "F.SilkS")
			(hide yes)
			(effects
				(font
					(size 1.27 1.27)
				)
			)
		)
		(property "Value" ""
			(at 0 0 0)
			(layer "F.Fab")
			(effects
				(font
					(size 1.27 1.27)
				)
			)
		)
		(duplicate_pad_numbers_are_jumpers no)
		(fp_line
			(start -0.7874 -0.4064)
			(end 0.7874 -0.4064)
			(stroke
				(width 0.1524)
				(type default)
			)
			(layer "F.SilkS")
		)
		(fp_line
			(start -0.7874 0.4064)
			(end -0.7874 -0.4064)
			(stroke
				(width 0.1524)
				(type default)
			)
			(layer "F.SilkS")
		)
		(fp_line
			(start 0.7874 -0.4064)
			(end 0.7874 0.4064)
			(stroke
				(width 0.1524)
				(type default)
			)
			(layer "F.SilkS")
		)
		(fp_line
			(start 0.7874 0.4064)
			(end -0.7874 0.4064)
			(stroke
				(width 0.1524)
				(type default)
			)
			(layer "F.SilkS")
		)
		(fp_line
			(start -0.67945 -0.305054)
			(end -0.12065 -0.305054)
			(stroke
				(width 0.1)
				(type default)
			)
			(layer "F.Fab")
		)
		(fp_line
			(start -0.67945 0.3048)
			(end -0.67945 -0.305054)
			(stroke
				(width 0.1)
				(type default)
			)
			(layer "F.Fab")
		)
		(fp_line
			(start -0.12065 -0.305054)
			(end -0.12065 -0.2794)
			(stroke
				(width 0.1)
				(type default)
			)
			(layer "F.Fab")
		)
		(fp_line
			(start -0.12065 -0.2794)
			(end 0.12065 -0.2794)
			(stroke
				(width 0.1)
				(type default)
			)
			(layer "F.Fab")
		)
		(fp_line
			(start -0.12065 0.2794)
			(end -0.12065 0.3048)
			(stroke
				(width 0.1)
				(type default)
			)
			(layer "F.Fab")
		)
		(fp_line
			(start -0.12065 0.3048)
			(end -0.67945 0.3048)
			(stroke
				(width 0.1)
				(type default)
			)
			(layer "F.Fab")
		)
		(fp_line
			(start 0.120396 0.2794)
			(end -0.12065 0.2794)
			(stroke
				(width 0.1)
				(type default)
			)
			(layer "F.Fab")
		)
		(fp_line
			(start 0.120396 0.3048)
			(end 0.120396 0.2794)
			(stroke
				(width 0.1)
				(type default)
			)
			(layer "F.Fab")
		)
		(fp_line
			(start 0.12065 -0.3048)
			(end 0.67945 -0.3048)
			(stroke
				(width 0.1)
				(type default)
			)
			(layer "F.Fab")
		)
		(fp_line
			(start 0.12065 -0.2794)
			(end 0.12065 -0.3048)
			(stroke
				(width 0.1)
				(type default)
			)
			(layer "F.Fab")
		)
		(fp_line
			(start 0.67945 -0.3048)
			(end 0.67945 0.3048)
			(stroke
				(width 0.1)
				(type default)
			)
			(layer "F.Fab")
		)
		(fp_line
			(start 0.67945 0.3048)
			(end 0.120396 0.3048)
			(stroke
				(width 0.1)
				(type default)
			)
			(layer "F.Fab")
		)
		(pad "1" smd circle
			(at -0.40005 0)
			(size 0 0)
			(layers "F.Cu" "F.Mask" "F.Paste")
			(net "P3V3_NIC7_OCP")
		)
		(pad "2" smd circle
			(at 0.40005 0)
			(size 0 0)
			(layers "F.Cu" "F.Mask" "F.Paste")
			(net "GND")
		)
	)
	(footprint ""
		(layer "F.Cu")
		(at 102.273862 -26.31186 -90)
		(property "Reference" "U401"
			(at -0.05334 -2.324608 90)
			(unlocked yes)
			(layer "F.SilkS")
			(effects
				(font
					(size 0.7874 0.5842)
					(thickness 0.1524)
				)
			)
		)
		(property "Value" ""
			(at 0 0 270)
			(layer "F.Fab")
			(effects
				(font
					(size 1.27 1.27)
				)
			)
		)
		(duplicate_pad_numbers_are_jumpers no)
		(fp_line
			(start -1.949958 1.610106)
			(end -1.949958 -1.610106)
			(stroke
				(width 0.1524)
				(type default)
			)
			(layer "F.SilkS")
		)
		(fp_line
			(start 1.949958 1.610106)
			(end -1.949958 1.610106)
			(stroke
				(width 0.1524)
				(type default)
			)
			(layer "F.SilkS")
		)
		(fp_line
			(start 1.949958 -1.560068)
			(end 1.949958 1.610106)
			(stroke
				(width 0.1524)
				(type default)
			)
			(layer "F.SilkS")
		)
		(fp_line
			(start -1.949958 -1.610106)
			(end 1.949958 -1.610106)
			(stroke
				(width 0.1524)
				(type default)
			)
			(layer "F.SilkS")
		)
		(fp_line
			(start -0.750062 1.560068)
			(end -0.750062 -1.560068)
			(stroke
				(width 0.1)
				(type default)
			)
			(layer "F.Fab")
		)
		(fp_line
			(start 0.750062 1.560068)
			(end -0.750062 1.560068)
			(stroke
				(width 0.1)
				(type default)
			)
			(layer "F.Fab")
		)
		(fp_line
			(start -0.750062 -1.560068)
			(end 0.750062 -1.560068)
			(stroke
				(width 0.1)
				(type default)
			)
			(layer "F.Fab")
		)
		(fp_line
			(start 0.750062 -1.560068)
			(end 0.750062 1.560068)
			(stroke
				(width 0.1)
				(type default)
			)
			(layer "F.Fab")
		)
		(pad "D" smd rect
			(at 1.100074 0 180)
			(size 1.016 1.4224)
			(layers "F.Cu" "F.Mask" "F.Paste")
			(net "SSD3_LED_ISO_N")
		)
		(pad "G" smd rect
			(at -1.100074 -0.94996 180)
			(size 1.016 1.4224)
			(layers "F.Cu" "F.Mask" "F.Paste")
			(net "SSD3_LED_R")
		)
		(pad "S" smd rect
			(at -1.100074 0.94996 180)
			(size 1.016 1.4224)
			(layers "F.Cu" "F.Mask" "F.Paste")
			(net "GND")
		)
	)
	(footprint ""
		(layer "F.Cu")
		(at 278.634444 -30.94609 180)
		(property "Reference" "C499"
			(at 0 0 180)
			(layer "F.SilkS")
			(hide yes)
			(effects
				(font
					(size 1.27 1.27)
				)
			)
		)
		(property "Value" ""
			(at 0 0 180)
			(layer "F.Fab")
			(effects
				(font
					(size 1.27 1.27)
				)
			)
		)
		(duplicate_pad_numbers_are_jumpers no)
		(fp_line
			(start 0.299974 0.150114)
			(end -0.299974 0.150114)
			(stroke
				(width 0.1)
				(type default)
			)
			(layer "F.Fab")
		)
		(fp_line
			(start 0.299974 -0.150114)
			(end 0.299974 0.150114)
			(stroke
				(width 0.1)
				(type default)
			)
			(layer "F.Fab")
		)
		(fp_line
			(start -0.299974 0.150114)
			(end -0.299974 -0.150114)
			(stroke
				(width 0.1)
				(type default)
			)
			(layer "F.Fab")
		)
		(fp_line
			(start -0.299974 -0.150114)
			(end 0.299974 -0.150114)
			(stroke
				(width 0.1)
				(type default)
			)
			(layer "F.Fab")
		)
		(pad "1" smd rect
			(at -0.2667 0 180)
			(size 0.3048 0.381)
			(layers "F.Cu" "F.Mask" "F.Paste")
			(net "P5E_PEX2_STN2_TX_DP<41>")
		)
		(pad "2" smd rect
			(at 0.2667 0 180)
			(size 0.3048 0.381)
			(layers "F.Cu" "F.Mask" "F.Paste")
			(net "P5E_PEX2_STN2_TX_C_DP<41>")
		)
	)
)
